(kicad_pcb
	(version 20260206)
	(generator "pcbnew")
	(generator_version "10.0")
	(general
		(thickness 1.6)
		(legacy_teardrops no)
	)
	(paper "A4")
	(title_block
		(title "m-2 — Lightning_M.2_BRD.brd")
		(comment 1 "Lightning (Wiwynn / Facebook NVMe JBOF) / footprints 82-83 of 157")
	)
	(layers
		(0 "F.Cu" signal "TOP")
		(4 "In1.Cu" signal "L2GND")
		(6 "In2.Cu" signal "L3")
		(8 "In3.Cu" signal "L4GND")
		(10 "In4.Cu" signal "L5GND")
		(12 "In5.Cu" signal "L6")
		(14 "In6.Cu" signal "L7GND")
		(2 "B.Cu" signal "BOTTOM")
		(9 "F.Adhes" user "F.Adhesive")
		(11 "B.Adhes" user "B.Adhesive")
		(13 "F.Paste" user "Package Geometry/Pastemask Top")
		(15 "B.Paste" user "Package Geometry/Pastemask Bottom")
		(5 "F.SilkS" user "Ref Des/Silkscreen Top")
		(7 "B.SilkS" user "Ref Des/Silkscreen Bottom")
		(1 "F.Mask" user "Board Geometry/Soldermask Top")
		(3 "B.Mask" user "Board Geometry/Soldermask Bottom")
		(17 "Dwgs.User" user "User.Drawings")
		(19 "Cmts.User" user "User.Comments")
		(21 "Eco1.User" user "User.Eco1")
		(23 "Eco2.User" user "User.Eco2")
		(25 "Edge.Cuts" user "Board Geometry/Outline")
		(27 "Margin" user)
		(31 "F.CrtYd" user "Package Geometry/Place Bound Top")
		(29 "B.CrtYd" user "Package Geometry/Place Bound Bottom")
		(35 "F.Fab" user "Ref Des/Assembly Top")
		(33 "B.Fab" user "Ref Des/Assembly Bottom")
	)
	(footprint ""
		(layer "F.Cu")
		(at 67.449954 -54.040024 -90)
		(property "Reference" "SSD_A1"
			(at 0 0 270)
			(layer "F.SilkS")
			(hide yes)
			(effects
				(font
					(size 1.27 1.27)
				)
			)
		)
		(property "Value" "SKT-MINI75P-11-GP"
			(at 12.6619 2.2733 270)
			(unlocked yes)
			(layer "F.Fab")
			(hide yes)
			(effects
				(font
					(size 1.016 1.016)
					(thickness 0.1524)
				)
			)
		)
		(property "Device Type" "MDT580M01001"
			(at 12.6619 0.7493 270)
			(unlocked yes)
			(layer "F.Fab")
			(hide yes)
			(effects
				(font
					(size 1.016 1.016)
					(thickness 0.1524)
				)
			)
		)
		(duplicate_pad_numbers_are_jumpers no)
		(fp_line
			(start -11.2522 3.302)
			(end -11.2522 -6.2992)
			(stroke
				(width 0.1524)
				(type default)
			)
			(layer "F.SilkS")
		)
		(fp_line
			(start 11.2522 3.302)
			(end -11.2522 3.302)
			(stroke
				(width 0.1524)
				(type default)
			)
			(layer "F.SilkS")
		)
		(fp_line
			(start -11.2522 -6.2992)
			(end 11.2522 -6.2992)
			(stroke
				(width 0.1524)
				(type default)
			)
			(layer "F.SilkS")
		)
		(fp_line
			(start 11.2522 -6.2992)
			(end 11.2522 3.302)
			(stroke
				(width 0.1524)
				(type default)
			)
			(layer "F.SilkS")
		)
		(fp_line
			(start -9.525 -6.3881)
			(end -9.017 -6.3881)
			(stroke
				(width 0.3302)
				(type default)
			)
			(layer "F.SilkS")
		)
		(fp_poly
			(pts
				(xy -9.273794 -6.315202) (xy -8.841994 -6.747002) (xy -9.705594 -6.747002)
			)
			(stroke
				(width 0)
				(type default)
			)
			(fill yes)
			(layer "F.SilkS")
		)
		(fp_rect
			(start -10.9982 2.8448)
			(end 10.9982 -5.6896)
			(stroke
				(width 0)
				(type default)
			)
			(fill no)
			(layer "F.CrtYd")
		)
		(fp_poly
			(pts
				(xy -11.5062 3.556) (xy -11.5062 -6.5532) (xy 11.5062 -6.5532) (xy 11.5062 -0.00635) (xy 10.9982 -0.00635)
				(xy 10.9982 -5.6896) (xy -10.9982 -5.6896) (xy -10.9982 2.8448) (xy 10.9982 2.8448) (xy 10.9982 0.00635)
				(xy 11.5062 0.00635) (xy 11.5062 3.556)
			)
			(stroke
				(width 0)
				(type default)
			)
			(fill no)
			(layer "F.CrtYd")
		)
		(fp_rect
			(start -11.5062 3.556)
			(end 11.5062 -6.5532)
			(stroke
				(width 0)
				(type default)
			)
			(fill no)
			(layer "F.Fab")
		)
		(pad "" np_thru_hole circle
			(at -9.99998 0 270)
			(size 0.254 0.254)
			(drill 1.1176)
			(layers "*.Cu" "*.Mask")
			(clearance 0.7874)
			(thermal_gap 0.7874)
		)
		(pad "" np_thru_hole circle
			(at 9.99998 0 270)
			(size 0.254 0.254)
			(drill 1.6002)
			(layers "*.Cu" "*.Mask")
			(clearance 1.0287)
			(thermal_gap 1.0287)
		)
		(pad "1" smd rect
			(at -9.249918 -5.275072 270)
			(size 0.3048 1.5494)
			(layers "F.Cu" "F.Mask" "F.Paste")
			(net "Z50_SSD_A_PRESENT_R#")
		)
		(pad "2" smd rect
			(at -8.999982 2.275078 270)
			(size 0.3048 1.5494)
			(layers "F.Cu" "F.Mask" "F.Paste")
			(net "P3V3_PWR")
		)
		(pad "3" smd rect
			(at -8.750046 -5.275072 270)
			(size 0.3048 1.5494)
			(layers "F.Cu" "F.Mask" "F.Paste")
			(net "GND")
		)
		(pad "4" smd rect
			(at -8.50011 2.275078 270)
			(size 0.3048 1.5494)
			(layers "F.Cu" "F.Mask" "F.Paste")
			(net "P3V3_PWR")
		)
		(pad "5" smd rect
			(at -8.24992 -5.275072 270)
			(size 0.3048 1.5494)
			(layers "F.Cu" "F.Mask" "F.Paste")
			(net "Net_145")
		)
		(pad "6" smd rect
			(at -7.999984 2.275078 270)
			(size 0.3048 1.5494)
			(layers "F.Cu" "F.Mask" "F.Paste")
			(net "Net_152")
		)
		(pad "7" smd rect
			(at -7.750048 -5.275072 270)
			(size 0.3048 1.5494)
			(layers "F.Cu" "F.Mask" "F.Paste")
			(net "Net_146")
		)
		(pad "8" smd rect
			(at -7.500112 2.275078 270)
			(size 0.3048 1.5494)
			(layers "F.Cu" "F.Mask" "F.Paste")
			(net "Net_153")
		)
		(pad "9" smd rect
			(at -7.249922 -5.275072 270)
			(size 0.3048 1.5494)
			(layers "F.Cu" "F.Mask" "F.Paste")
			(net "GND")
		)
		(pad "10" smd rect
			(at -6.999986 2.275078 270)
			(size 0.3048 1.5494)
			(layers "F.Cu" "F.Mask" "F.Paste")
			(net "Z50_SSD_A_R_ACT#")
		)
		(pad "11" smd rect
			(at -6.75005 -5.275072 270)
			(size 0.3048 1.5494)
			(layers "F.Cu" "F.Mask" "F.Paste")
			(net "Net_147")
		)
		(pad "12" smd rect
			(at -6.500114 2.275078 270)
			(size 0.3048 1.5494)
			(layers "F.Cu" "F.Mask" "F.Paste")
			(net "P3V3_PWR")
		)
		(pad "13" smd rect
			(at -6.249924 -5.275072 270)
			(size 0.3048 1.5494)
			(layers "F.Cu" "F.Mask" "F.Paste")
			(net "Net_148")
		)
		(pad "14" smd rect
			(at -5.999988 2.275078 270)
			(size 0.3048 1.5494)
			(layers "F.Cu" "F.Mask" "F.Paste")
			(net "P3V3_PWR")
		)
		(pad "15" smd rect
			(at -5.750052 -5.275072 270)
			(size 0.3048 1.5494)
			(layers "F.Cu" "F.Mask" "F.Paste")
			(net "GND")
		)
		(pad "16" smd rect
			(at -5.500116 2.275078 270)
			(size 0.3048 1.5494)
			(layers "F.Cu" "F.Mask" "F.Paste")
			(net "P3V3_PWR")
		)
		(pad "17" smd rect
			(at -5.249926 -5.275072 270)
			(size 0.3048 1.5494)
			(layers "F.Cu" "F.Mask" "F.Paste")
			(net "Net_149")
		)
		(pad "18" smd rect
			(at -4.99999 2.275078 270)
			(size 0.3048 1.5494)
			(layers "F.Cu" "F.Mask" "F.Paste")
			(net "P3V3_PWR")
		)
		(pad "19" smd rect
			(at -4.750054 -5.275072 270)
			(size 0.3048 1.5494)
			(layers "F.Cu" "F.Mask" "F.Paste")
			(net "Net_150")
		)
		(pad "20" smd rect
			(at -4.500118 2.275078 270)
			(size 0.3048 1.5494)
			(layers "F.Cu" "F.Mask" "F.Paste")
			(net "Net_154")
		)
		(pad "21" smd rect
			(at -4.249928 -5.275072 270)
			(size 0.3048 1.5494)
			(layers "F.Cu" "F.Mask" "F.Paste")
			(net "GND")
		)
		(pad "22" smd rect
			(at -3.999992 2.275078 270)
			(size 0.3048 1.5494)
			(layers "F.Cu" "F.Mask" "F.Paste")
			(net "Net_155")
		)
		(pad "23" smd rect
			(at -3.750056 -5.275072 270)
			(size 0.3048 1.5494)
			(layers "F.Cu" "F.Mask" "F.Paste")
			(net "Net_151")
		)
		(pad "24" smd rect
			(at -3.50012 2.275078 270)
			(size 0.3048 1.5494)
			(layers "F.Cu" "F.Mask" "F.Paste")
			(net "Net_135")
		)
		(pad "25" smd rect
			(at -3.24993 -5.275072 270)
			(size 0.3048 1.5494)
			(layers "F.Cu" "F.Mask" "F.Paste")
			(net "Net_134")
		)
		(pad "26" smd rect
			(at -2.999994 2.275078 270)
			(size 0.3048 1.5494)
			(layers "F.Cu" "F.Mask" "F.Paste")
			(net "Net_136")
		)
		(pad "27" smd rect
			(at -2.750058 -5.275072 270)
			(size 0.3048 1.5494)
			(layers "F.Cu" "F.Mask" "F.Paste")
			(net "GND")
		)
		(pad "28" smd rect
			(at -2.500122 2.275078 270)
			(size 0.3048 1.5494)
			(layers "F.Cu" "F.Mask" "F.Paste")
			(net "Net_137")
		)
		(pad "29" smd rect
			(at -2.249932 -5.275072 270)
			(size 0.3048 1.5494)
			(layers "F.Cu" "F.Mask" "F.Paste")
			(net "D85_PCIE_A_RX0_N")
		)
		(pad "30" smd rect
			(at -1.999996 2.275078 270)
			(size 0.3048 1.5494)
			(layers "F.Cu" "F.Mask" "F.Paste")
			(net "Net_138")
		)
		(pad "31" smd rect
			(at -1.75006 -5.275072 270)
			(size 0.3048 1.5494)
			(layers "F.Cu" "F.Mask" "F.Paste")
			(net "D85_PCIE_A_RX0_P")
		)
		(pad "32" smd rect
			(at -1.500124 2.275078 270)
			(size 0.3048 1.5494)
			(layers "F.Cu" "F.Mask" "F.Paste")
			(net "Net_139")
		)
		(pad "33" smd rect
			(at -1.249934 -5.275072 270)
			(size 0.3048 1.5494)
			(layers "F.Cu" "F.Mask" "F.Paste")
			(net "GND")
		)
		(pad "34" smd rect
			(at -0.999998 2.275078 270)
			(size 0.3048 1.5494)
			(layers "F.Cu" "F.Mask" "F.Paste")
			(net "Net_140")
		)
		(pad "35" smd rect
			(at -0.750062 -5.275072 270)
			(size 0.3048 1.5494)
			(layers "F.Cu" "F.Mask" "F.Paste")
			(net "D85_PCIE_A_TX0_P")
		)
		(pad "36" smd rect
			(at -0.500126 2.275078 270)
			(size 0.3048 1.5494)
			(layers "F.Cu" "F.Mask" "F.Paste")
			(net "Net_141")
		)
		(pad "37" smd rect
			(at -0.249936 -5.275072 270)
			(size 0.3048 1.5494)
			(layers "F.Cu" "F.Mask" "F.Paste")
			(net "D85_PCIE_A_TX0_N")
		)
		(pad "38" smd rect
			(at 0 2.275078 270)
			(size 0.3048 1.5494)
			(layers "F.Cu" "F.Mask" "F.Paste")
			(net "Net_142")
		)
		(pad "39" smd rect
			(at 0.249936 -5.275072 270)
			(size 0.3048 1.5494)
			(layers "F.Cu" "F.Mask" "F.Paste")
			(net "GND")
		)
		(pad "40" smd rect
			(at 0.500126 2.275078 270)
			(size 0.3048 1.5494)
			(layers "F.Cu" "F.Mask" "F.Paste")
			(net "Z50_SSD_A1_SMB_CLK")
		)
		(pad "41" smd rect
			(at 0.750062 -5.275072 270)
			(size 0.3048 1.5494)
			(layers "F.Cu" "F.Mask" "F.Paste")
			(net "D85_PCIE_A_RX1_N")
		)
		(pad "42" smd rect
			(at 0.999998 2.275078 270)
			(size 0.3048 1.5494)
			(layers "F.Cu" "F.Mask" "F.Paste")
			(net "Z50_SSD_A1_SMB_DATA")
		)
		(pad "43" smd rect
			(at 1.249934 -5.275072 270)
			(size 0.3048 1.5494)
			(layers "F.Cu" "F.Mask" "F.Paste")
			(net "D85_PCIE_A_RX1_P")
		)
		(pad "44" smd rect
			(at 1.500124 2.275078 270)
			(size 0.3048 1.5494)
			(layers "F.Cu" "F.Mask" "F.Paste")
			(net "Z50_SSD_A1_ALERT#")
		)
		(pad "45" smd rect
			(at 1.75006 -5.275072 270)
			(size 0.3048 1.5494)
			(layers "F.Cu" "F.Mask" "F.Paste")
			(net "GND")
		)
		(pad "46" smd rect
			(at 1.999996 2.275078 270)
			(size 0.3048 1.5494)
			(layers "F.Cu" "F.Mask" "F.Paste")
			(net "Net_143")
		)
		(pad "47" smd rect
			(at 2.249932 -5.275072 270)
			(size 0.3048 1.5494)
			(layers "F.Cu" "F.Mask" "F.Paste")
			(net "D85_PCIE_A_TX1_P")
		)
		(pad "48" smd rect
			(at 2.500122 2.275078 270)
			(size 0.3048 1.5494)
			(layers "F.Cu" "F.Mask" "F.Paste")
			(net "Net_144")
		)
		(pad "49" smd rect
			(at 2.750058 -5.275072 270)
			(size 0.3048 1.5494)
			(layers "F.Cu" "F.Mask" "F.Paste")
			(net "D85_PCIE_A_TX1_N")
		)
		(pad "50" smd rect
			(at 2.999994 2.275078 270)
			(size 0.3048 1.5494)
			(layers "F.Cu" "F.Mask" "F.Paste")
			(net "Z50_DEV_RST#")
		)
		(pad "51" smd rect
			(at 3.24993 -5.275072 270)
			(size 0.3048 1.5494)
			(layers "F.Cu" "F.Mask" "F.Paste")
			(net "GND")
		)
		(pad "52" smd rect
			(at 3.50012 2.275078 270)
			(size 0.3048 1.5494)
			(layers "F.Cu" "F.Mask" "F.Paste")
			(net "Z50_SSD_A1_CLKREQ#")
		)
		(pad "53" smd rect
			(at 3.750056 -5.275072 270)
			(size 0.3048 1.5494)
			(layers "F.Cu" "F.Mask" "F.Paste")
			(net "D85_PCIE_A_REFCLK_N")
		)
		(pad "54" smd rect
			(at 3.999992 2.275078 270)
			(size 0.3048 1.5494)
			(layers "F.Cu" "F.Mask" "F.Paste")
			(net "Net_131")
		)
		(pad "55" smd rect
			(at 4.249928 -5.275072 270)
			(size 0.3048 1.5494)
			(layers "F.Cu" "F.Mask" "F.Paste")
			(net "D85_PCIE_A_REFCLK_P")
		)
		(pad "56" smd rect
			(at 4.500118 2.275078 270)
			(size 0.3048 1.5494)
			(layers "F.Cu" "F.Mask" "F.Paste")
			(net "SSD_A1_MFG_DATA_TP")
		)
		(pad "57" smd rect
			(at 4.750054 -5.275072 270)
			(size 0.3048 1.5494)
			(layers "F.Cu" "F.Mask" "F.Paste")
			(net "GND")
		)
		(pad "58" smd rect
			(at 4.99999 2.275078 270)
			(size 0.3048 1.5494)
			(layers "F.Cu" "F.Mask" "F.Paste")
			(net "SSD_A1_MFG_CLK_TP")
		)
		(pad "67" smd rect
			(at 7.249922 -5.275072 270)
			(size 0.3048 1.5494)
			(layers "F.Cu" "F.Mask" "F.Paste")
			(net "Net_129")
		)
		(pad "68" smd rect
			(at 7.500112 2.275078 270)
			(size 0.3048 1.5494)
			(layers "F.Cu" "F.Mask" "F.Paste")
			(net "Net_132")
		)
		(pad "69" smd rect
			(at 7.750048 -5.275072 270)
			(size 0.3048 1.5494)
			(layers "F.Cu" "F.Mask" "F.Paste")
			(net "Net_130")
		)
		(pad "70" smd rect
			(at 7.999984 2.275078 270)
			(size 0.3048 1.5494)
			(layers "F.Cu" "F.Mask" "F.Paste")
			(net "P3V3_PWR")
		)
		(pad "71" smd rect
			(at 8.24992 -5.275072 270)
			(size 0.3048 1.5494)
			(layers "F.Cu" "F.Mask" "F.Paste")
			(net "GND")
		)
		(pad "72" smd rect
			(at 8.50011 2.275078 270)
			(size 0.3048 1.5494)
			(layers "F.Cu" "F.Mask" "F.Paste")
			(net "P3V3_PWR")
		)
		(pad "73" smd rect
			(at 8.750046 -5.275072 270)
			(size 0.3048 1.5494)
			(layers "F.Cu" "F.Mask" "F.Paste")
			(net "GND")
		)
		(pad "74" smd rect
			(at 8.999982 2.275078 270)
			(size 0.3048 1.5494)
			(layers "F.Cu" "F.Mask" "F.Paste")
			(net "P3V3_PWR")
		)
		(pad "75" smd rect
			(at 9.249918 -5.275072 270)
			(size 0.3048 1.5494)
			(layers "F.Cu" "F.Mask" "F.Paste")
			(net "GND")
		)
		(pad "76" smd rect
			(at -10.349992 -4.500118 270)
			(size 1.1938 2.7432)
			(layers "F.Cu" "F.Mask" "F.Paste")
			(net "GND")
		)
		(pad "77" smd rect
			(at 10.349992 -4.500118 270)
			(size 1.1938 2.7432)
			(layers "F.Cu" "F.Mask" "F.Paste")
			(net "GND")
		)
		(zone
			(layer "F.Cu")
			(hatch none 0.5)
			(connect_pads
				(clearance 0)
			)
			(min_thickness 0.25)
			(keepout
				(tracks allowed)
				(vias not_allowed)
				(pads allowed)
				(copperpour not_allowed)
				(footprints allowed)
			)
			(placement
				(enabled no)
				(sheetname "")
			)
			(fill
				(thermal_gap 0.5)
				(thermal_bridge_width 0.5)
				(island_removal_mode 0)
			)
			(polygon
				(pts
					(xy 65.949576 -63.192406) (xy 65.949576 -48.887634) (xy 66.457576 -48.887634) (xy 66.457576 -63.192406)
				)
			)
		)
		(zone
			(layer "F.Cu")
			(hatch none 0.5)
			(connect_pads
				(clearance 0)
			)
			(min_thickness 0.25)
			(keepout
				(tracks allowed)
				(vias not_allowed)
				(pads allowed)
				(copperpour not_allowed)
				(footprints allowed)
			)
			(placement
				(enabled no)
				(sheetname "")
			)
			(fill
				(thermal_gap 0.5)
				(thermal_bridge_width 0.5)
				(island_removal_mode 0)
			)
			(polygon
				(pts
					(xy 65.949576 -46.692312) (xy 65.949576 -44.887642) (xy 66.457576 -44.887642) (xy 66.457576 -46.692312)
				)
			)
		)
		(zone
			(layer "F.Cu")
			(hatch none 0.5)
			(connect_pads
				(clearance 0)
			)
			(min_thickness 0.25)
			(keepout
				(tracks allowed)
				(vias not_allowed)
				(pads allowed)
				(copperpour not_allowed)
				(footprints allowed)
			)
			(placement
				(enabled no)
				(sheetname "")
			)
			(fill
				(thermal_gap 0.5)
				(thermal_bridge_width 0.5)
				(island_removal_mode 0)
			)
			(polygon
				(pts
					(xy 71.442326 -63.442342) (xy 71.442326 -49.13757) (xy 71.950326 -49.13757) (xy 71.950326 -63.442342)
				)
			)
		)
		(zone
			(layer "F.Cu")
			(hatch none 0.5)
			(connect_pads
				(clearance 0)
			)
			(min_thickness 0.25)
			(keepout
				(tracks allowed)
				(vias not_allowed)
				(pads allowed)
				(copperpour not_allowed)
				(footprints allowed)
			)
			(placement
				(enabled no)
				(sheetname "")
			)
			(fill
				(thermal_gap 0.5)
				(thermal_bridge_width 0.5)
				(island_removal_mode 0)
			)
			(polygon
				(pts
					(xy 71.442326 -46.942502) (xy 71.442326 -44.637706) (xy 71.950326 -44.637706) (xy 71.950326 -46.942502)
				)
			)
		)
		(zone
			(layers "F.Cu" "B.Cu" "In1.Cu" "In2.Cu" "In3.Cu" "In4.Cu" "In5.Cu" "In6.Cu")
			(hatch none 0.5)
			(connect_pads
				(clearance 0)
			)
			(min_thickness 0.25)
			(keepout
				(tracks not_allowed)
				(vias allowed)
				(pads allowed)
				(copperpour not_allowed)
				(footprints allowed)
			)
			(placement
				(enabled no)
				(sheetname "")
			)
			(fill
				(thermal_gap 0.5)
				(thermal_bridge_width 0.5)
				(island_removal_mode 0)
			)
			(polygon
				(pts
					(arc
						(start 68.313554 -64.040004)
						(mid 66.586354 -64.040004)
						(end 68.313554 -64.040004)
					)
				)
			)
		)
		(zone
			(layers "F.Cu" "B.Cu" "In1.Cu" "In2.Cu" "In3.Cu" "In4.Cu" "In5.Cu" "In6.Cu")
			(hatch none 0.5)
			(connect_pads
				(clearance 0)
			)
			(min_thickness 0.25)
			(keepout
				(tracks not_allowed)
				(vias allowed)
				(pads allowed)
				(copperpour not_allowed)
				(footprints allowed)
			)
			(placement
				(enabled no)
				(sheetname "")
			)
			(fill
				(thermal_gap 0.5)
				(thermal_bridge_width 0.5)
				(island_removal_mode 0)
			)
			(polygon
				(pts
					(arc
						(start 68.554854 -44.040044)
						(mid 66.345054 -44.040044)
						(end 68.554854 -44.040044)
					)
				)
			)
		)
	)
	(footprint ""
		(layer "F.Cu")
		(at 59.817 -44.577 -90)
		(property "Reference" "C1"
			(at 0 0 270)
			(layer "F.SilkS")
			(hide yes)
			(effects
				(font
					(size 1.27 1.27)
				)
			)
		)
		(property "Value" "SC1U6D3V2KX-9-GP"
			(at 1.1811 -2.7051 270)
			(unlocked yes)
			(layer "F.Fab")
			(hide yes)
			(effects
				(font
					(size 1.016 1.016)
					(thickness 0.1524)
				)
			)
		)
		(property "Device Type" "C402H22"
			(at 1.1811 -4.2291 270)
			(unlocked yes)
			(layer "F.Fab")
			(hide yes)
			(effects
				(font
					(size 1.016 1.016)
					(thickness 0.1524)
				)
			)
		)
		(duplicate_pad_numbers_are_jumpers no)
		(fp_rect
			(start -0.4318 0.9525)
			(end 0.4318 -0.9525)
			(stroke
				(width 0)
				(type default)
			)
			(fill no)
			(layer "F.CrtYd")
		)
		(fp_rect
			(start -0.4318 0.9525)
			(end 0.4318 -0.9525)
			(stroke
				(width 0)
				(type default)
			)
			(fill no)
			(layer "F.Fab")
		)
		(pad "1" smd custom
			(at 0 -0.4445 270)
			(size 0.1524 0.1524)
			(layers "F.Cu" "F.Mask" "F.Paste")
			(net "P3V3_PWR")
			(options
				(clearance outline)
				(anchor circle)
			)
			(primitives
				(gr_poly
					(pts
						(arc
							(start 0.3048 -0.2032)
							(mid 0.275042 -0.275042)
							(end 0.2032 -0.3048)
						)
						(arc
							(start -0.2032 -0.3048)
							(mid -0.275042 -0.275042)
							(end -0.3048 -0.2032)
						)
						(arc
							(start -0.3048 0.2032)
							(mid -0.275042 0.275042)
							(end -0.2032 0.3048)
						)
						(arc
							(start 0.2032 0.3048)
							(mid 0.275042 0.275042)
							(end 0.3048 0.2032)
						)
					)
					(width 0)
					(fill yes)
				)
			)
		)
		(pad "2" smd custom
			(at 0 0.4445 270)
			(size 0.1524 0.1524)
			(layers "F.Cu" "F.Mask" "F.Paste")
			(net "GND")
			(options
				(clearance outline)
				(anchor circle)
			)
			(primitives
				(gr_poly
					(pts
						(arc
							(start 0.3048 -0.2032)
							(mid 0.275042 -0.275042)
							(end 0.2032 -0.3048)
						)
						(arc
							(start -0.2032 -0.3048)
							(mid -0.275042 -0.275042)
							(end -0.3048 -0.2032)
						)
						(arc
							(start -0.3048 0.2032)
							(mid -0.275042 0.275042)
							(end -0.2032 0.3048)
						)
						(arc
							(start 0.2032 0.3048)
							(mid 0.275042 0.275042)
							(end 0.3048 0.2032)
						)
					)
					(width 0)
					(fill yes)
				)
			)
		)
	)
)
